(kicad_pcb
	(version 20260206)
	(generator "pcbnew")
	(generator_version "10.0")
	(general
		(thickness 1.6)
		(legacy_teardrops no)
	)
	(paper "A4")
	(title_block
		(title "03242023_DA0F0TMBIJ0_F0T_Motherboard_J_brd_V01_OCP.brd")
		(comment 1 "Grand Teton / footprints 1108-1113 of 6105")
	)
	(layers
		(0 "F.Cu" signal "TOP")
		(4 "In1.Cu" signal "GND")
		(6 "In2.Cu" signal "IN1")
		(8 "In3.Cu" signal "GND1")
		(10 "In4.Cu" signal "IN2")
		(12 "In5.Cu" signal "GND2")
		(14 "In6.Cu" signal "IN3")
		(16 "In7.Cu" signal "GND3")
		(18 "In8.Cu" signal "VCC")
		(20 "In9.Cu" signal "VCC1")
		(22 "In10.Cu" signal "GND4")
		(24 "In11.Cu" signal "IN4")
		(26 "In12.Cu" signal "GND5")
		(28 "In13.Cu" signal "IN5")
		(30 "In14.Cu" signal "GND6")
		(32 "In15.Cu" signal "IN6")
		(34 "In16.Cu" signal "GND7")
		(2 "B.Cu" signal "BOTTOM")
		(9 "F.Adhes" user "F.Adhesive")
		(11 "B.Adhes" user "B.Adhesive")
		(13 "F.Paste" user "Package Geometry/Pastemask Top")
		(15 "B.Paste" user "Package Geometry/Pastemask Bottom")
		(5 "F.SilkS" user "Ref Des/Silkscreen Top")
		(7 "B.SilkS" user "Ref Des/Silkscreen Bottom")
		(1 "F.Mask" user "Board Geometry/Soldermask Top")
		(3 "B.Mask" user "Board Geometry/Soldermask Bottom")
		(17 "Dwgs.User" user "User.Drawings")
		(19 "Cmts.User" user "User.Comments")
		(21 "Eco1.User" user "User.Eco1")
		(23 "Eco2.User" user "User.Eco2")
		(25 "Edge.Cuts" user "Board Geometry/Outline")
		(27 "Margin" user)
		(31 "F.CrtYd" user "Package Geometry/Place Bound Top")
		(29 "B.CrtYd" user "Package Geometry/Place Bound Bottom")
		(35 "F.Fab" user "Ref Des/Assembly Top")
		(33 "B.Fab" user "Ref Des/Assembly Bottom")
	)
	(footprint ""
		(layer "F.Cu")
		(at 274.495006 -19.952462)
		(property "Reference" "R3184"
			(at 0 0 0)
			(layer "F.SilkS")
			(hide yes)
			(effects
				(font
					(size 1.27 1.27)
				)
			)
		)
		(property "Value" ""
			(at 0 0 0)
			(layer "F.Fab")
			(effects
				(font
					(size 1.27 1.27)
				)
			)
		)
		(duplicate_pad_numbers_are_jumpers no)
		(fp_line
			(start -0.7874 -0.4064)
			(end 0.7874 -0.4064)
			(stroke
				(width 0.1524)
				(type default)
			)
			(layer "F.SilkS")
		)
		(fp_line
			(start -0.7874 0.4064)
			(end -0.7874 -0.4064)
			(stroke
				(width 0.1524)
				(type default)
			)
			(layer "F.SilkS")
		)
		(fp_line
			(start 0.7874 -0.4064)
			(end 0.7874 0.4064)
			(stroke
				(width 0.1524)
				(type default)
			)
			(layer "F.SilkS")
		)
		(fp_line
			(start 0.7874 0.4064)
			(end -0.7874 0.4064)
			(stroke
				(width 0.1524)
				(type default)
			)
			(layer "F.SilkS")
		)
		(fp_line
			(start -0.67945 -0.305054)
			(end -0.12065 -0.305054)
			(stroke
				(width 0.1)
				(type default)
			)
			(layer "F.Fab")
		)
		(fp_line
			(start -0.67945 0.3048)
			(end -0.67945 -0.305054)
			(stroke
				(width 0.1)
				(type default)
			)
			(layer "F.Fab")
		)
		(fp_line
			(start -0.12065 -0.305054)
			(end -0.12065 -0.2794)
			(stroke
				(width 0.1)
				(type default)
			)
			(layer "F.Fab")
		)
		(fp_line
			(start -0.12065 -0.2794)
			(end 0.12065 -0.2794)
			(stroke
				(width 0.1)
				(type default)
			)
			(layer "F.Fab")
		)
		(fp_line
			(start -0.12065 0.2794)
			(end -0.12065 0.3048)
			(stroke
				(width 0.1)
				(type default)
			)
			(layer "F.Fab")
		)
		(fp_line
			(start -0.12065 0.3048)
			(end -0.67945 0.3048)
			(stroke
				(width 0.1)
				(type default)
			)
			(layer "F.Fab")
		)
		(fp_line
			(start 0.120396 0.2794)
			(end -0.12065 0.2794)
			(stroke
				(width 0.1)
				(type default)
			)
			(layer "F.Fab")
		)
		(fp_line
			(start 0.120396 0.3048)
			(end 0.120396 0.2794)
			(stroke
				(width 0.1)
				(type default)
			)
			(layer "F.Fab")
		)
		(fp_line
			(start 0.12065 -0.3048)
			(end 0.67945 -0.3048)
			(stroke
				(width 0.1)
				(type default)
			)
			(layer "F.Fab")
		)
		(fp_line
			(start 0.12065 -0.2794)
			(end 0.12065 -0.3048)
			(stroke
				(width 0.1)
				(type default)
			)
			(layer "F.Fab")
		)
		(fp_line
			(start 0.67945 -0.3048)
			(end 0.67945 0.3048)
			(stroke
				(width 0.1)
				(type default)
			)
			(layer "F.Fab")
		)
		(fp_line
			(start 0.67945 0.3048)
			(end 0.120396 0.3048)
			(stroke
				(width 0.1)
				(type default)
			)
			(layer "F.Fab")
		)
		(pad "1" smd circle
			(at -0.40005 0)
			(size 0 0)
			(layers "F.Cu" "F.Mask" "F.Paste")
			(net "P3V3_AUX")
		)
		(pad "2" smd circle
			(at 0.40005 0)
			(size 0 0)
			(layers "F.Cu" "F.Mask" "F.Paste")
			(net "OCP_V3_2_WAKE_BUFF_N")
		)
	)
	(footprint ""
		(layer "F.Cu")
		(at 9.58088 -56.982868)
		(property "Reference" "R3060"
			(at 0 0 0)
			(layer "F.SilkS")
			(hide yes)
			(effects
				(font
					(size 1.27 1.27)
				)
			)
		)
		(property "Value" ""
			(at 0 0 0)
			(layer "F.Fab")
			(effects
				(font
					(size 1.27 1.27)
				)
			)
		)
		(duplicate_pad_numbers_are_jumpers no)
		(fp_line
			(start -0.7874 -0.4064)
			(end 0.7874 -0.4064)
			(stroke
				(width 0.1524)
				(type default)
			)
			(layer "F.SilkS")
		)
		(fp_line
			(start -0.7874 0.4064)
			(end -0.7874 -0.4064)
			(stroke
				(width 0.1524)
				(type default)
			)
			(layer "F.SilkS")
		)
		(fp_line
			(start 0.7874 -0.4064)
			(end 0.7874 0.4064)
			(stroke
				(width 0.1524)
				(type default)
			)
			(layer "F.SilkS")
		)
		(fp_line
			(start 0.7874 0.4064)
			(end -0.7874 0.4064)
			(stroke
				(width 0.1524)
				(type default)
			)
			(layer "F.SilkS")
		)
		(fp_line
			(start -0.67945 -0.305054)
			(end -0.12065 -0.305054)
			(stroke
				(width 0.1)
				(type default)
			)
			(layer "F.Fab")
		)
		(fp_line
			(start -0.67945 0.3048)
			(end -0.67945 -0.305054)
			(stroke
				(width 0.1)
				(type default)
			)
			(layer "F.Fab")
		)
		(fp_line
			(start -0.12065 -0.305054)
			(end -0.12065 -0.2794)
			(stroke
				(width 0.1)
				(type default)
			)
			(layer "F.Fab")
		)
		(fp_line
			(start -0.12065 -0.2794)
			(end 0.12065 -0.2794)
			(stroke
				(width 0.1)
				(type default)
			)
			(layer "F.Fab")
		)
		(fp_line
			(start -0.12065 0.2794)
			(end -0.12065 0.3048)
			(stroke
				(width 0.1)
				(type default)
			)
			(layer "F.Fab")
		)
		(fp_line
			(start -0.12065 0.3048)
			(end -0.67945 0.3048)
			(stroke
				(width 0.1)
				(type default)
			)
			(layer "F.Fab")
		)
		(fp_line
			(start 0.120396 0.2794)
			(end -0.12065 0.2794)
			(stroke
				(width 0.1)
				(type default)
			)
			(layer "F.Fab")
		)
		(fp_line
			(start 0.120396 0.3048)
			(end 0.120396 0.2794)
			(stroke
				(width 0.1)
				(type default)
			)
			(layer "F.Fab")
		)
		(fp_line
			(start 0.12065 -0.3048)
			(end 0.67945 -0.3048)
			(stroke
				(width 0.1)
				(type default)
			)
			(layer "F.Fab")
		)
		(fp_line
			(start 0.12065 -0.2794)
			(end 0.12065 -0.3048)
			(stroke
				(width 0.1)
				(type default)
			)
			(layer "F.Fab")
		)
		(fp_line
			(start 0.67945 -0.3048)
			(end 0.67945 0.3048)
			(stroke
				(width 0.1)
				(type default)
			)
			(layer "F.Fab")
		)
		(fp_line
			(start 0.67945 0.3048)
			(end 0.120396 0.3048)
			(stroke
				(width 0.1)
				(type default)
			)
			(layer "F.Fab")
		)
		(pad "1" smd circle
			(at -0.40005 0)
			(size 0 0)
			(layers "F.Cu" "F.Mask" "F.Paste")
			(net "SMB_SML1_PMBUS_3V3AUX_PCH_SCL")
		)
		(pad "2" smd circle
			(at 0.40005 0)
			(size 0 0)
			(layers "F.Cu" "F.Mask" "F.Paste")
			(net "SMB_PMBUS_SML1_ME_SCL")
		)
	)
	(footprint ""
		(layer "F.Cu")
		(at 393.316206 -155.356052 -90)
		(property "Reference" "U30"
			(at 0.617474 -3.043174 0)
			(unlocked yes)
			(layer "F.SilkS")
			(effects
				(font
					(size 0.7874 0.5842)
					(thickness 0.1524)
				)
				(justify left)
			)
		)
		(property "Value" ""
			(at 0 0 270)
			(layer "F.Fab")
			(effects
				(font
					(size 1.27 1.27)
				)
			)
		)
		(duplicate_pad_numbers_are_jumpers no)
		(fp_line
			(start -1.4224 2.5146)
			(end 1.4224 2.5146)
			(stroke
				(width 0.1524)
				(type default)
			)
			(layer "F.SilkS")
		)
		(fp_line
			(start 1.4224 2.5146)
			(end 1.4224 -2.5146)
			(stroke
				(width 0.1524)
				(type default)
			)
			(layer "F.SilkS")
		)
		(fp_line
			(start 0 -2.0574)
			(end -0.4572 -2.5146)
			(stroke
				(width 0.1524)
				(type default)
			)
			(layer "F.SilkS")
		)
		(fp_line
			(start -1.4224 -2.5146)
			(end -1.4224 2.5146)
			(stroke
				(width 0.1524)
				(type default)
			)
			(layer "F.SilkS")
		)
		(fp_line
			(start -0.4572 -2.5146)
			(end -1.4224 -2.5146)
			(stroke
				(width 0.1524)
				(type default)
			)
			(layer "F.SilkS")
		)
		(fp_line
			(start 0.4572 -2.5146)
			(end 0 -2.0574)
			(stroke
				(width 0.1524)
				(type default)
			)
			(layer "F.SilkS")
		)
		(fp_line
			(start 1.4224 -2.5146)
			(end 0.4572 -2.5146)
			(stroke
				(width 0.1524)
				(type default)
			)
			(layer "F.SilkS")
		)
		(fp_poly
			(pts
				(xy -3.080004 -3.230118) (xy -2.318004 -3.230118) (xy -2.699004 -2.468118)
			)
			(stroke
				(width 0)
				(type default)
			)
			(fill yes)
			(layer "F.SilkS")
		)
		(fp_line
			(start -2.0066 2.5146)
			(end 2.0066 2.5146)
			(stroke
				(width 0.1)
				(type default)
			)
			(layer "F.Fab")
		)
		(fp_line
			(start 2.0066 2.5146)
			(end 2.0066 2.112264)
			(stroke
				(width 0.1)
				(type default)
			)
			(layer "F.Fab")
		)
		(fp_line
			(start -2.648712 2.112264)
			(end -2.0066 2.112264)
			(stroke
				(width 0.1)
				(type default)
			)
			(layer "F.Fab")
		)
		(fp_line
			(start -2.0066 2.112264)
			(end -2.0066 2.5146)
			(stroke
				(width 0.1)
				(type default)
			)
			(layer "F.Fab")
		)
		(fp_line
			(start 2.0066 2.112264)
			(end 2.642616 2.112264)
			(stroke
				(width 0.1)
				(type default)
			)
			(layer "F.Fab")
		)
		(fp_line
			(start 2.642616 2.112264)
			(end 2.642616 -2.112264)
			(stroke
				(width 0.1)
				(type default)
			)
			(layer "F.Fab")
		)
		(fp_line
			(start 2.0066 -2.112264)
			(end 2.0066 -2.5146)
			(stroke
				(width 0.1)
				(type default)
			)
			(layer "F.Fab")
		)
		(fp_line
			(start 2.642616 -2.112264)
			(end 2.0066 -2.112264)
			(stroke
				(width 0.1)
				(type default)
			)
			(layer "F.Fab")
		)
		(fp_line
			(start -2.648712 -2.114804)
			(end -2.648712 2.112264)
			(stroke
				(width 0.1)
				(type default)
			)
			(layer "F.Fab")
		)
		(fp_line
			(start -2.0066 -2.114804)
			(end -2.648712 -2.114804)
			(stroke
				(width 0.1)
				(type default)
			)
			(layer "F.Fab")
		)
		(fp_line
			(start -2.0066 -2.5146)
			(end -2.0066 -2.114804)
			(stroke
				(width 0.1)
				(type default)
			)
			(layer "F.Fab")
		)
		(fp_line
			(start 2.0066 -2.5146)
			(end -2.0066 -2.5146)
			(stroke
				(width 0.1)
				(type default)
			)
			(layer "F.Fab")
		)
		(fp_poly
			(pts
				(xy -3.6322 -1.869186) (xy -4.3942 -1.488186) (xy -4.3942 -2.250186)
			)
			(stroke
				(width 0)
				(type default)
			)
			(fill yes)
			(layer "F.Fab")
		)
		(pad "1" smd rect
			(at -2.6416 -1.905 180)
			(size 0.5588 1.7272)
			(layers "F.Cu" "F.Mask" "F.Paste")
			(net "PVNN_TERM_CPU0")
		)
		(pad "2" smd rect
			(at -2.6416 -0.635 180)
			(size 0.5588 1.7272)
			(layers "F.Cu" "F.Mask" "F.Paste")
			(net "SMB_S3M_CPU0_R_SCL")
		)
		(pad "3" smd rect
			(at -2.6416 0.635 180)
			(size 0.5588 1.7272)
			(layers "F.Cu" "F.Mask" "F.Paste")
			(net "SMB_S3M_CPU0_R_SDA")
		)
		(pad "4" smd rect
			(at -2.6416 1.905 180)
			(size 0.5588 1.7272)
			(layers "F.Cu" "F.Mask" "F.Paste")
			(net "GND")
		)
		(pad "5" smd rect
			(at 2.6416 1.905 180)
			(size 0.5588 1.7272)
			(layers "F.Cu" "F.Mask" "F.Paste")
			(net "TP_SMB_S3M_CPU0_EN")
		)
		(pad "6" smd rect
			(at 2.6416 0.635 180)
			(size 0.5588 1.7272)
			(layers "F.Cu" "F.Mask" "F.Paste")
			(net "SMB_S3M_CPU0_3V3AUX_SDA")
		)
		(pad "7" smd rect
			(at 2.6416 -0.635 180)
			(size 0.5588 1.7272)
			(layers "F.Cu" "F.Mask" "F.Paste")
			(net "SMB_S3M_CPU0_3V3AUX_SCL")
		)
		(pad "8" smd rect
			(at 2.6416 -1.905 180)
			(size 0.5588 1.7272)
			(layers "F.Cu" "F.Mask" "F.Paste")
			(net "P3V3_AUX")
		)
	)
	(footprint ""
		(layer "F.Cu")
		(at 170.23588 -126.964948 90)
		(property "Reference" "R984"
			(at 0 0 90)
			(layer "F.SilkS")
			(hide yes)
			(effects
				(font
					(size 1.27 1.27)
				)
			)
		)
		(property "Value" ""
			(at 0 0 90)
			(layer "F.Fab")
			(effects
				(font
					(size 1.27 1.27)
				)
			)
		)
		(duplicate_pad_numbers_are_jumpers no)
		(fp_line
			(start 0.7874 -0.4064)
			(end 0.7874 0.4064)
			(stroke
				(width 0.1524)
				(type default)
			)
			(layer "F.SilkS")
		)
		(fp_line
			(start -0.7874 -0.4064)
			(end 0.7874 -0.4064)
			(stroke
				(width 0.1524)
				(type default)
			)
			(layer "F.SilkS")
		)
		(fp_line
			(start 0.7874 0.4064)
			(end -0.7874 0.4064)
			(stroke
				(width 0.1524)
				(type default)
			)
			(layer "F.SilkS")
		)
		(fp_line
			(start -0.7874 0.4064)
			(end -0.7874 -0.4064)
			(stroke
				(width 0.1524)
				(type default)
			)
			(layer "F.SilkS")
		)
		(fp_line
			(start -0.12065 -0.305054)
			(end -0.12065 -0.2794)
			(stroke
				(width 0.1)
				(type default)
			)
			(layer "F.Fab")
		)
		(fp_line
			(start -0.67945 -0.305054)
			(end -0.12065 -0.305054)
			(stroke
				(width 0.1)
				(type default)
			)
			(layer "F.Fab")
		)
		(fp_line
			(start 0.67945 -0.3048)
			(end 0.67945 0.3048)
			(stroke
				(width 0.1)
				(type default)
			)
			(layer "F.Fab")
		)
		(fp_line
			(start 0.12065 -0.3048)
			(end 0.67945 -0.3048)
			(stroke
				(width 0.1)
				(type default)
			)
			(layer "F.Fab")
		)
		(fp_line
			(start 0.12065 -0.2794)
			(end 0.12065 -0.3048)
			(stroke
				(width 0.1)
				(type default)
			)
			(layer "F.Fab")
		)
		(fp_line
			(start -0.12065 -0.2794)
			(end 0.12065 -0.2794)
			(stroke
				(width 0.1)
				(type default)
			)
			(layer "F.Fab")
		)
		(fp_line
			(start 0.120396 0.2794)
			(end -0.12065 0.2794)
			(stroke
				(width 0.1)
				(type default)
			)
			(layer "F.Fab")
		)
		(fp_line
			(start -0.12065 0.2794)
			(end -0.12065 0.3048)
			(stroke
				(width 0.1)
				(type default)
			)
			(layer "F.Fab")
		)
		(fp_line
			(start 0.67945 0.3048)
			(end 0.120396 0.3048)
			(stroke
				(width 0.1)
				(type default)
			)
			(layer "F.Fab")
		)
		(fp_line
			(start 0.120396 0.3048)
			(end 0.120396 0.2794)
			(stroke
				(width 0.1)
				(type default)
			)
			(layer "F.Fab")
		)
		(fp_line
			(start -0.12065 0.3048)
			(end -0.67945 0.3048)
			(stroke
				(width 0.1)
				(type default)
			)
			(layer "F.Fab")
		)
		(fp_line
			(start -0.67945 0.3048)
			(end -0.67945 -0.305054)
			(stroke
				(width 0.1)
				(type default)
			)
			(layer "F.Fab")
		)
		(pad "1" smd circle
			(at -0.40005 0 90)
			(size 0 0)
			(layers "F.Cu" "F.Mask" "F.Paste")
			(net "FM_PVCCFA_EHV_FIVRA_CPU0_R_EN")
		)
		(pad "2" smd circle
			(at 0.40005 0 90)
			(size 0 0)
			(layers "F.Cu" "F.Mask" "F.Paste")
			(net "FM_PVCCFA_EHV_FIVRA_CPU0_EN")
		)
	)
	(footprint ""
		(layer "F.Cu")
		(at 449.350638 -335.460594 -90)
		(property "Reference" "R1838"
			(at 0 0 270)
			(layer "F.SilkS")
			(hide yes)
			(effects
				(font
					(size 1.27 1.27)
				)
			)
		)
		(property "Value" ""
			(at 0 0 270)
			(layer "F.Fab")
			(effects
				(font
					(size 1.27 1.27)
				)
			)
		)
		(duplicate_pad_numbers_are_jumpers no)
		(fp_line
			(start -4.0386 1.7526)
			(end -4.0386 -1.7526)
			(stroke
				(width 0.1524)
				(type default)
			)
			(layer "F.SilkS")
		)
		(fp_line
			(start 4.0386 1.7526)
			(end -4.0386 1.7526)
			(stroke
				(width 0.1524)
				(type default)
			)
			(layer "F.SilkS")
		)
		(fp_line
			(start -4.0386 -1.7526)
			(end 4.0386 -1.7526)
			(stroke
				(width 0.1524)
				(type default)
			)
			(layer "F.SilkS")
		)
		(fp_line
			(start 4.0386 -1.7526)
			(end 4.0386 1.7526)
			(stroke
				(width 0.1524)
				(type default)
			)
			(layer "F.SilkS")
		)
		(fp_line
			(start -4.0386 1.7526)
			(end -4.0386 -1.7526)
			(stroke
				(width 0.1)
				(type default)
			)
			(layer "F.Fab")
		)
		(fp_line
			(start 4.0386 1.7526)
			(end -4.0386 1.7526)
			(stroke
				(width 0.1)
				(type default)
			)
			(layer "F.Fab")
		)
		(fp_line
			(start -4.0386 -1.7526)
			(end 4.0386 -1.7526)
			(stroke
				(width 0.1)
				(type default)
			)
			(layer "F.Fab")
		)
		(fp_line
			(start 4.0386 -1.7526)
			(end 4.0386 1.7526)
			(stroke
				(width 0.1)
				(type default)
			)
			(layer "F.Fab")
		)
		(pad "1" smd circle
			(at -3.700018 0 180)
			(size 0 0)
			(layers "F.Cu" "F.Mask" "F.Paste")
			(net "P12V_AUX")
		)
		(pad "2" smd circle
			(at 3.700018 0)
			(size 0 0)
			(layers "F.Cu" "F.Mask" "F.Paste")
			(net "P12V_S3_AUX_CPU0_NVDIMM")
		)
		(pad "3" smd rect
			(at -2.70002 0)
			(size 0.4064 1.1176)
			(layers "F.Cu" "F.Mask" "F.Paste")
			(net "P12V_AUX_CPU0_DIMM_ISEN_P")
		)
		(pad "4" smd rect
			(at 2.70002 0)
			(size 0.4064 1.1176)
			(layers "F.Cu" "F.Mask" "F.Paste")
			(net "P12V_AUX_CPU0_DIMM_ISEN_N")
		)
	)
	(footprint ""
		(layer "F.Cu")
		(at 496.64493 -470.91219)
		(property "Reference" "U2_BL"
			(at 0.11049 -3.433318 0)
			(unlocked yes)
			(layer "F.SilkS")
			(effects
				(font
					(size 0.7874 0.5842)
					(thickness 0.1524)
				)
				(justify left)
			)
		)
		(property "Value" ""
			(at 0 0 0)
			(layer "F.Fab")
			(effects
				(font
					(size 1.27 1.27)
				)
			)
		)
		(duplicate_pad_numbers_are_jumpers no)
		(pad "1" smd circle
			(at 0 0)
			(size 0.762 0.762)
			(layers "F.Cu" "F.Mask" "F.Paste")
			(net "Net_8485")
		)
	)
)
